(kicad_sch
	(version 20250114)
	(generator "eeschema")
	(generator_version "9.0")
	(paper "A3")
	(title_block
		(title "SO-DIMM DDR5 Tester")
		(date "2025-11-26")
		(rev "1.3.0")
		(company "Antmicro Ltd.")
		(comment 1 "www.antmicro.com")
		(comment 2 "Antmicro Ltd")
	)
	(text "Connected to 3V3 for increased ESD protection"
		(exclude_from_sim no)
		(at 83.82 71.755 0)
		(effects
			(font
				(size 1.27 1.27)
			)
			(justify left bottom)
		)
	)
	(text "BANK 13"
		(exclude_from_sim no)
		(at 13.335 18.415 0)
		(effects
			(font
				(size 2.54 2.54)
				(thickness 0.5994)
				(bold yes)
			)
			(justify left bottom)
		)
	)
	(text "BANK 15"
		(exclude_from_sim no)
		(at 212.725 19.05 0)
		(effects
			(font
				(size 2.54 2.54)
				(thickness 0.5994)
				(bold yes)
			)
			(justify left bottom)
		)
	)
	(text "Connected to 3V3 for increased ESD protection"
		(exclude_from_sim no)
		(at 267.335 73.025 0)
		(effects
			(font
				(size 1.27 1.27)
			)
			(justify left bottom)
		)
	)
	(junction
		(at 278.13 83.82)
		(diameter 0)
		(color 0 0 0 0)
	)
	(junction
		(at 93.98 83.82)
		(diameter 0)
		(color 0 0 0 0)
	)
	(no_connect
		(at 96.52 144.78)
	)
	(no_connect
		(at 280.67 116.84)
	)
	(no_connect
		(at 280.67 162.56)
	)
	(no_connect
		(at 96.52 154.94)
	)
	(no_connect
		(at 96.52 114.3)
	)
	(no_connect
		(at 280.67 119.38)
	)
	(no_connect
		(at 280.67 104.14)
	)
	(no_connect
		(at 280.67 144.78)
	)
	(no_connect
		(at 280.67 167.64)
	)
	(no_connect
		(at 96.52 162.56)
	)
	(no_connect
		(at 96.52 213.36)
	)
	(no_connect
		(at 280.67 127)
	)
	(no_connect
		(at 96.52 175.26)
	)
	(no_connect
		(at 96.52 119.38)
	)
	(no_connect
		(at 280.67 205.74)
	)
	(no_connect
		(at 280.67 170.18)
	)
	(no_connect
		(at 96.52 195.58)
	)
	(no_connect
		(at 96.52 190.5)
	)
	(no_connect
		(at 280.67 106.68)
	)
	(no_connect
		(at 96.52 170.18)
	)
	(no_connect
		(at 96.52 172.72)
	)
	(no_connect
		(at 96.52 104.14)
	)
	(no_connect
		(at 280.67 88.9)
	)
	(no_connect
		(at 280.67 182.88)
	)
	(no_connect
		(at 280.67 149.86)
	)
	(no_connect
		(at 280.67 137.16)
	)
	(no_connect
		(at 96.52 198.12)
	)
	(no_connect
		(at 96.52 185.42)
	)
	(no_connect
		(at 280.67 160.02)
	)
	(no_connect
		(at 96.52 167.64)
	)
	(no_connect
		(at 280.67 142.24)
	)
	(no_connect
		(at 280.67 91.44)
	)
	(no_connect
		(at 96.52 165.1)
	)
	(no_connect
		(at 280.67 172.72)
	)
	(no_connect
		(at 280.67 147.32)
	)
	(no_connect
		(at 280.67 190.5)
	)
	(no_connect
		(at 96.52 121.92)
	)
	(no_connect
		(at 280.67 132.08)
	)
	(no_connect
		(at 96.52 101.6)
	)
	(no_connect
		(at 96.52 147.32)
	)
	(no_connect
		(at 96.52 152.4)
	)
	(no_connect
		(at 280.67 180.34)
	)
	(no_connect
		(at 280.67 154.94)
	)
	(no_connect
		(at 280.67 139.7)
	)
	(no_connect
		(at 96.52 137.16)
	)
	(no_connect
		(at 280.67 175.26)
	)
	(no_connect
		(at 280.67 129.54)
	)
	(no_connect
		(at 280.67 93.98)
	)
	(no_connect
		(at 280.67 101.6)
	)
	(no_connect
		(at 280.67 165.1)
	)
	(no_connect
		(at 280.67 124.46)
	)
	(no_connect
		(at 96.52 91.44)
	)
	(no_connect
		(at 96.52 139.7)
	)
	(no_connect
		(at 96.52 208.28)
	)
	(no_connect
		(at 96.52 142.24)
	)
	(no_connect
		(at 280.67 134.62)
	)
	(no_connect
		(at 280.67 203.2)
	)
	(no_connect
		(at 280.67 96.52)
	)
	(no_connect
		(at 96.52 187.96)
	)
	(no_connect
		(at 96.52 132.08)
	)
	(no_connect
		(at 280.67 213.36)
	)
	(no_connect
		(at 96.52 129.54)
	)
	(no_connect
		(at 280.67 200.66)
	)
	(no_connect
		(at 280.67 185.42)
	)
	(no_connect
		(at 280.67 193.04)
	)
	(no_connect
		(at 280.67 157.48)
	)
	(no_connect
		(at 280.67 208.28)
	)
	(no_connect
		(at 96.52 106.68)
	)
	(no_connect
		(at 96.52 124.46)
	)
	(no_connect
		(at 96.52 160.02)
	)
	(no_connect
		(at 280.67 99.06)
	)
	(no_connect
		(at 280.67 195.58)
	)
	(no_connect
		(at 96.52 127)
	)
	(no_connect
		(at 96.52 200.66)
	)
	(no_connect
		(at 96.52 193.04)
	)
	(no_connect
		(at 96.52 134.62)
	)
	(no_connect
		(at 96.52 88.9)
	)
	(no_connect
		(at 96.52 205.74)
	)
	(no_connect
		(at 96.52 111.76)
	)
	(no_connect
		(at 280.67 111.76)
	)
	(no_connect
		(at 96.52 203.2)
	)
	(no_connect
		(at 280.67 177.8)
	)
	(no_connect
		(at 96.52 99.06)
	)
	(no_connect
		(at 96.52 93.98)
	)
	(no_connect
		(at 96.52 180.34)
	)
	(no_connect
		(at 280.67 187.96)
	)
	(no_connect
		(at 96.52 109.22)
	)
	(no_connect
		(at 96.52 96.52)
	)
	(no_connect
		(at 280.67 152.4)
	)
	(no_connect
		(at 280.67 109.22)
	)
	(no_connect
		(at 280.67 210.82)
	)
	(no_connect
		(at 280.67 114.3)
	)
	(no_connect
		(at 280.67 198.12)
	)
	(no_connect
		(at 96.52 116.84)
	)
	(no_connect
		(at 96.52 149.86)
	)
	(no_connect
		(at 280.67 121.92)
	)
	(no_connect
		(at 96.52 210.82)
	)
	(no_connect
		(at 96.52 177.8)
	)
	(no_connect
		(at 96.52 157.48)
	)
	(no_connect
		(at 96.52 182.88)
	)
	(wire
		(pts
			(xy 93.98 83.82) (xy 96.52 83.82)
		)
		(stroke
			(width 0)
			(type default)
		)
	)
	(wire
		(pts
			(xy 278.13 83.185) (xy 278.13 83.82)
		)
		(stroke
			(width 0)
			(type default)
		)
	)
	(wire
		(pts
			(xy 278.13 83.82) (xy 280.67 83.82)
		)
		(stroke
			(width 0)
			(type default)
		)
	)
	(wire
		(pts
			(xy 93.98 83.185) (xy 93.98 83.82)
		)
		(stroke
			(width 0)
			(type default)
		)
	)
	(wire
		(pts
			(xy 273.05 83.82) (xy 278.13 83.82)
		)
		(stroke
			(width 0)
			(type default)
		)
	)
	(wire
		(pts
			(xy 88.9 83.82) (xy 93.98 83.82)
		)
		(stroke
			(width 0)
			(type default)
		)
	)
	(wire
		(pts
			(xy 80.01 83.82) (xy 83.82 83.82)
		)
		(stroke
			(width 0)
			(type default)
		)
	)
	(wire
		(pts
			(xy 264.16 81.915) (xy 264.16 83.82)
		)
		(stroke
			(width 0)
			(type default)
		)
	)
	(polyline
		(pts
			(xy 210.185 12.065) (xy 210.185 284.48)
		)
		(stroke
			(width 0)
			(type default)
		)
	)
	(wire
		(pts
			(xy 80.01 81.915) (xy 80.01 83.82)
		)
		(stroke
			(width 0)
			(type default)
		)
	)
	(wire
		(pts
			(xy 264.16 83.82) (xy 267.97 83.82)
		)
		(stroke
			(width 0)
			(type default)
		)
	)
	(symbol
		(lib_id "antmicroFPGAChips:XC7K160T-FFG676")
		(at 280.67 83.82 0)
		(unit 4)
		(exclude_from_sim no)
		(in_bom yes)
		(on_board yes)
		(dnp no)
		(fields_autoplaced yes)
		(property "Reference" "U4"
			(at 322.072 147.7594 0)
			(effects
				(font
					(size 1.27 1.27)
				)
				(justify left)
			)
		)
		(property "Value" "XC7K160T-FFG676"
			(at 322.072 150.2897 0)
			(effects
				(font
					(size 1.27 1.27)
					(thickness 0.15)
				)
				(justify left)
			)
		)
		(property "Footprint" "antmicro-footprints:BGA-676_27x27mm_Layout26x26_P1x1mm_FFG676"
			(at 349.25 86.36 0)
			(effects
				(font
					(size 1.27 1.27)
					(thickness 0.15)
				)
				(justify left bottom)
				(hide yes)
			)
		)
		(property "Datasheet" "https://docs.xilinx.com/v/u/en-US/ds180_7Series_Overview"
			(at 349.25 88.9 0)
			(effects
				(font
					(size 1.27 1.27)
					(thickness 0.15)
				)
				(justify left bottom)
				(hide yes)
			)
		)
		(property "Description" ""
			(at 280.67 83.82 0)
			(effects
				(font
					(size 1.27 1.27)
				)
			)
		)
		(property "MPN" "XC7K160T-FFG676"
			(at 280.67 83.82 0)
			(effects
				(font
					(size 1.27 1.27)
				)
				(hide yes)
			)
		)
		(property "Author" "Antmicro"
			(at 349.25 91.44 0)
			(effects
				(font
					(size 1.27 1.27)
					(thickness 0.15)
				)
				(justify left bottom)
				(hide yes)
			)
		)
		(property "License" "Apache-2.0"
			(at 349.25 93.98 0)
			(effects
				(font
					(size 1.27 1.27)
					(thickness 0.15)
				)
				(justify left bottom)
				(hide yes)
			)
		)
		(property "Manufacturer" "AMD-Xilinx"
			(at 280.67 83.82 0)
			(effects
				(font
					(size 1.27 1.27)
				)
				(hide yes)
			)
		)
		(pin "AA21"
		)
		(pin "AA22"
		)
		(pin "AA23"
		)
		(pin "AA24"
		)
		(pin "AA25"
		)
		(pin "AB21"
		)
		(pin "AB22"
		)
		(pin "AB24"
		)
		(pin "AB25"
		)
		(pin "AB26"
		)
		(pin "AC21"
		)
		(pin "AC22"
		)
		(pin "AC23"
		)
		(pin "AC24"
		)
		(pin "AC25"
		)
		(pin "AC26"
		)
		(pin "AD21"
		)
		(pin "AD22"
		)
		(pin "AD23"
		)
		(pin "AD24"
		)
		(pin "AD25"
		)
		(pin "AD26"
		)
		(pin "AE21"
		)
		(pin "AE22"
		)
		(pin "AE23"
		)
		(pin "AE25"
		)
		(pin "AE26"
		)
		(pin "AF22"
		)
		(pin "AF23"
		)
		(pin "AF24"
		)
		(pin "AF25"
		)
		(pin "AF26"
		)
		(pin "U21"
		)
		(pin "U22"
		)
		(pin "U23"
		)
		(pin "U24"
		)
		(pin "U25"
		)
		(pin "U26"
		)
		(pin "V20"
		)
		(pin "V21"
		)
		(pin "V22"
		)
		(pin "V23"
		)
		(pin "V24"
		)
		(pin "V26"
		)
		(pin "W20"
		)
		(pin "W21"
		)
		(pin "W23"
		)
		(pin "W24"
		)
		(pin "W25"
		)
		(pin "W26"
		)
		(pin "Y20"
		)
		(pin "Y21"
		)
		(pin "Y22"
		)
		(pin "Y23"
		)
		(pin "Y24"
		)
		(pin "Y25"
		)
		(pin "Y26"
		)
		(pin "K24"
		)
		(pin "K25"
		)
		(pin "K26"
		)
		(pin "L24"
		)
		(pin "L25"
		)
		(pin "M19"
		)
		(pin "M20"
		)
		(pin "M21"
		)
		(pin "M22"
		)
		(pin "M24"
		)
		(pin "M25"
		)
		(pin "M26"
		)
		(pin "N16"
		)
		(pin "N17"
		)
		(pin "N18"
		)
		(pin "N19"
		)
		(pin "N21"
		)
		(pin "N22"
		)
		(pin "N23"
		)
		(pin "N24"
		)
		(pin "N25"
		)
		(pin "N26"
		)
		(pin "P16"
		)
		(pin "P18"
		)
		(pin "P19"
		)
		(pin "P20"
		)
		(pin "P21"
		)
		(pin "P22"
		)
		(pin "P23"
		)
		(pin "P24"
		)
		(pin "P25"
		)
		(pin "P26"
		)
		(pin "R16"
		)
		(pin "R17"
		)
		(pin "R18"
		)
		(pin "R19"
		)
		(pin "R20"
		)
		(pin "R21"
		)
		(pin "R22"
		)
		(pin "R23"
		)
		(pin "R25"
		)
		(pin "R26"
		)
		(pin "T16"
		)
		(pin "T17"
		)
		(pin "T18"
		)
		(pin "T19"
		)
		(pin "T20"
		)
		(pin "T22"
		)
		(pin "T23"
		)
		(pin "T24"
		)
		(pin "T25"
		)
		(pin "T26"
		)
		(pin "U16"
		)
		(pin "U17"
		)
		(pin "U19"
		)
		(pin "U20"
		)
		(pin "A20"
		)
		(pin "A21"
		)
		(pin "A22"
		)
		(pin "A23"
		)
		(pin "A24"
		)
		(pin "A25"
		)
		(pin "B20"
		)
		(pin "B21"
		)
		(pin "B22"
		)
		(pin "B24"
		)
		(pin "B25"
		)
		(pin "B26"
		)
		(pin "C21"
		)
		(pin "C22"
		)
		(pin "C23"
		)
		(pin "C24"
		)
		(pin "C25"
		)
		(pin "C26"
		)
		(pin "D21"
		)
		(pin "D22"
		)
		(pin "D23"
		)
		(pin "D24"
		)
		(pin "D25"
		)
		(pin "D26"
		)
		(pin "E21"
		)
		(pin "E22"
		)
		(pin "E23"
		)
		(pin "E25"
		)
		(pin "E26"
		)
		(pin "F22"
		)
		(pin "F23"
		)
		(pin "F24"
		)
		(pin "F25"
		)
		(pin "F26"
		)
		(pin "G21"
		)
		(pin "G22"
		)
		(pin "G23"
		)
		(pin "G24"
		)
		(pin "G25"
		)
		(pin "G26"
		)
		(pin "H21"
		)
		(pin "H22"
		)
		(pin "H23"
		)
		(pin "H24"
		)
		(pin "H26"
		)
		(pin "J21"
		)
		(pin "J23"
		)
		(pin "J24"
		)
		(pin "J25"
		)
		(pin "J26"
		)
		(pin "K21"
		)
		(pin "K22"
		)
		(pin "K23"
		)
		(pin "L21"
		)
		(pin "L22"
		)
		(pin "L23"
		)
		(pin "A17"
		)
		(pin "A18"
		)
		(pin "A19"
		)
		(pin "B16"
		)
		(pin "B17"
		)
		(pin "B18"
		)
		(pin "B19"
		)
		(pin "C16"
		)
		(pin "C17"
		)
		(pin "C18"
		)
		(pin "C19"
		)
		(pin "D15"
		)
		(pin "D16"
		)
		(pin "D18"
		)
		(pin "D19"
		)
		(pin "D20"
		)
		(pin "E15"
		)
		(pin "E16"
		)
		(pin "E17"
		)
		(pin "E18"
		)
		(pin "E19"
		)
		(pin "E20"
		)
		(pin "F15"
		)
		(pin "F16"
		)
		(pin "F17"
		)
		(pin "F18"
		)
		(pin "F19"
		)
		(pin "F20"
		)
		(pin "G15"
		)
		(pin "G16"
		)
		(pin "G17"
		)
		(pin "G19"
		)
		(pin "G20"
		)
		(pin "H16"
		)
		(pin "H17"
		)
		(pin "H18"
		)
		(pin "H19"
		)
		(pin "H20"
		)
		(pin "J15"
		)
		(pin "J16"
		)
		(pin "J17"
		)
		(pin "J18"
		)
		(pin "J19"
		)
		(pin "J20"
		)
		(pin "K15"
		)
		(pin "K16"
		)
		(pin "K17"
		)
		(pin "K18"
		)
		(pin "K20"
		)
		(pin "L17"
		)
		(pin "L18"
		)
		(pin "L19"
		)
		(pin "L20"
		)
		(pin "M16"
		)
		(pin "M17"
		)
		(pin "M18"
		)
		(pin "A10"
		)
		(pin "A11"
		)
		(pin "A12"
		)
		(pin "A13"
		)
		(pin "A14"
		)
		(pin "A15"
		)
		(pin "A8"
		)
		(pin "A9"
		)
		(pin "B10"
		)
		(pin "B11"
		)
		(pin "B12"
		)
		(pin "B14"
		)
		(pin "B15"
		)
		(pin "B8"
		)
		(pin "B9"
		)
		(pin "C11"
		)
		(pin "C12"
		)
		(pin "C13"
		)
		(pin "C14"
		)
		(pin "C15"
		)
		(pin "C9"
		)
		(pin "D10"
		)
		(pin "D11"
		)
		(pin "D12"
		)
		(pin "D13"
		)
		(pin "D14"
		)
		(pin "D8"
		)
		(pin "D9"
		)
		(pin "E10"
		)
		(pin "E11"
		)
		(pin "E12"
		)
		(pin "E13"
		)
		(pin "E9"
		)
		(pin "F10"
		)
		(pin "F12"
		)
		(pin "F13"
		)
		(pin "F14"
		)
		(pin "F8"
		)
		(pin "F9"
		)
		(pin "G10"
		)
		(pin "G11"
		)
		(pin "G12"
		)
		(pin "G13"
		)
		(pin "G14"
		)
		(pin "G9"
		)
		(pin "H10"
		)
		(pin "H11"
		)
		(pin "H12"
		)
		(pin "H13"
		)
		(pin "H14"
		)
		(pin "H8"
		)
		(pin "H9"
		)
		(pin "J10"
		)
		(pin "J11"
		)
		(pin "J13"
		)
		(pin "J14"
		)
		(pin "J8"
		)
		(pin "AA14"
		)
		(pin "AA15"
		)
		(pin "AA17"
		)
		(pin "AA18"
		)
		(pin "AA19"
		)
		(pin "AA20"
		)
		(pin "AB14"
		)
		(pin "AB15"
		)
		(pin "AB16"
		)
		(pin "AB17"
		)
		(pin "AB18"
		)
		(pin "AB19"
		)
		(pin "AB20"
		)
		(pin "AC14"
		)
		(pin "AC15"
		)
		(pin "AC16"
		)
		(pin "AC17"
		)
		(pin "AC18"
		)
		(pin "AC19"
		)
		(pin "AD14"
		)
		(pin "AD15"
		)
		(pin "AD16"
		)
		(pin "AD18"
		)
		(pin "AD19"
		)
		(pin "AD20"
		)
		(pin "AE15"
		)
		(pin "AE16"
		)
		(pin "AE17"
		)
		(pin "AE18"
		)
		(pin "AE19"
		)
		(pin "AE20"
		)
		(pin "AF14"
		)
		(pin "AF15"
		)
		(pin "AF16"
		)
		(pin "AF17"
		)
		(pin "AF18"
		)
		(pin "AF19"
		)
		(pin "AF20"
		)
		(pin "V13"
		)
		(pin "V14"
		)
		(pin "V16"
		)
		(pin "V17"
		)
		(pin "V18"
		)
		(pin "V19"
		)
		(pin "W13"
		)
		(pin "W14"
		)
		(pin "W15"
		)
		(pin "W16"
		)
		(pin "W17"
		)
		(pin "W18"
		)
		(pin "W19"
		)
		(pin "Y14"
		)
		(pin "Y15"
		)
		(pin "Y16"
		)
		(pin "Y17"
		)
		(pin "Y18"
		)
		(pin "AA10"
		)
		(pin "AA11"
		)
		(pin "AA12"
		)
		(pin "AA13"
		)
		(pin "AA7"
		)
		(pin "AA8"
		)
		(pin "AA9"
		)
		(pin "AB10"
		)
		(pin "AB11"
		)
		(pin "AB12"
		)
		(pin "AB7"
		)
		(pin "AB8"
		)
		(pin "AB9"
		)
		(pin "AC11"
		)
		(pin "AC12"
		)
		(pin "AC13"
		)
		(pin "AC7"
		)
		(pin "AC8"
		)
		(pin "AC9"
		)
		(pin "AD10"
		)
		(pin "AD11"
		)
		(pin "AD12"
		)
		(pin "AD13"
		)
		(pin "AD8"
		)
		(pin "AD9"
		)
		(pin "AE10"
		)
		(pin "AE11"
		)
		(pin "AE12"
		)
		(pin "AE13"
		)
		(pin "AE7"
		)
		(pin "AE8"
		)
		(pin "AE9"
		)
		(pin "AF10"
		)
		(pin "AF12"
		)
		(pin "AF13"
		)
		(pin "AF7"
		)
		(pin "AF8"
		)
		(pin "AF9"
		)
		(pin "U9"
		)
		(pin "V10"
		)
		(pin "V11"
		)
		(pin "V12"
		)
		(pin "V7"
		)
		(pin "V8"
		)
		(pin "V9"
		)
		(pin "W10"
		)
		(pin "W11"
		)
		(pin "W7"
		)
		(pin "W8"
		)
		(pin "W9"
		)
		(pin "Y10"
		)
		(pin "Y11"
		)
		(pin "Y12"
		)
		(pin "Y13"
		)
		(pin "Y7"
		)
		(pin "Y8"
		)
		(pin "AA1"
		)
		(pin "AA2"
		)
		(pin "AA3"
		)
		(pin "AA4"
		)
		(pin "AA5"
		)
		(pin "AB1"
		)
		(pin "AB2"
		)
		(pin "AB4"
		)
		(pin "AB5"
		)
		(pin "AB6"
		)
		(pin "AC1"
		)
		(pin "AC2"
		)
		(pin "AC3"
		)
		(pin "AC4"
		)
		(pin "AC5"
		)
		(pin "AC6"
		)
		(pin "AD1"
		)
		(pin "AD2"
		)
		(pin "AD3"
		)
		(pin "AD4"
		)
		(pin "AD5"
		)
		(pin "AD6"
		)
		(pin "AE1"
		)
		(pin "AE2"
		)
		(pin "AE3"
		)
		(pin "AE5"
		)
		(pin "AE6"
		)
		(pin "AF2"
		)
		(pin "AF3"
		)
		(pin "AF4"
		)
		(pin "AF5"
		)
		(pin "AF6"
		)
		(pin "T7"
		)
		(pin "U1"
		)
		(pin "U2"
		)
		(pin "U3"
		)
		(pin "U4"
		)
		(pin "U5"
		)
		(pin "U6"
		)
		(pin "U7"
		)
		(pin "V1"
		)
		(pin "V2"
		)
		(pin "V3"
		)
		(pin "V4"
		)
		(pin "V6"
		)
		(pin "W1"
		)
		(pin "W3"
		)
		(pin "W4"
		)
		(pin "W5"
		)
		(pin "W6"
		)
		(pin "Y1"
		)
		(pin "Y2"
		)
		(pin "Y3"
		)
		(pin "Y4"
		)
		(pin "Y5"
		)
		(pin "Y6"
		)
		(pin "A3"
		)
		(pin "A4"
		)
		(pin "B1"
		)
		(pin "B2"
		)
		(pin "B5"
		)
		(pin "B6"
		)
		(pin "C3"
		)
		(pin "C4"
		)
		(pin "D1"
		)
		(pin "D2"
		)
		(pin "D5"
		)
		(pin "D6"
		)
		(pin "E3"
		)
		(pin "E4"
		)
		(pin "F1"
		)
		(pin "F2"
		)
		(pin "F5"
		)
		(pin "F6"
		)
		(pin "G3"
		)
		(pin "G4"
		)
		(pin "H1"
		)
		(pin "H2"
		)
		(pin "H5"
		)
		(pin "H6"
		)
		(pin "J3"
		)
		(pin "J4"
		)
		(pin "K1"
		)
		(pin "K2"
		)
		(pin "K5"
		)
		(pin "K6"
		)
		(pin "L3"
		)
		(pin "L4"
		)
		(pin "M1"
		)
		(pin "M2"
		)
		(pin "N3"
		)
		(pin "N4"
		)
		(pin "P1"
		)
		(pin "P2"
		)
		(pin "R3"
		)
		(pin "R4"
		)
		(pin "A1"
		)
		(pin "A16"
		)
		(pin "A2"
		)
		(pin "A26"
		)
		(pin "A5"
		)
		(pin "A6"
		)
		(pin "A7"
		)
		(pin "AA16"
		)
		(pin "AA26"
		)
		(pin "AA6"
		)
		(pin "AB13"
		)
		(pin "AB23"
		)
		(pin "AB3"
		)
		(pin "AC10"
		)
		(pin "AC20"
		)
		(pin "AD17"
		)
		(pin "AD7"
		)
		(pin "AE14"
		)
		(pin "AE24"
		)
		(pin "AE4"
		)
		(pin "AF1"
		)
		(pin "AF11"
		)
		(pin "AF21"
		)
		(pin "B13"
		)
		(pin "B23"
		)
		(pin "B3"
		)
		(pin "B4"
		)
		(pin "B7"
		)
		(pin "C1"
		)
		(pin "C10"
		)
		(pin "C2"
		)
		(pin "C20"
		)
		(pin "C5"
		)
		(pin "C6"
		)
		(pin "C7"
		)
		(pin "D17"
		)
		(pin "D3"
		)
		(pin "D4"
		)
		(pin "D7"
		)
		(pin "E1"
		)
		(pin "E14"
		)
		(pin "E2"
		)
		(pin "E24"
		)
		(pin "E5"
		)
		(pin "E6"
		)
		(pin "E7"
		)
		(pin "E8"
		)
		(pin "F11"
		)
		(pin "F21"
		)
		(pin "F3"
		)
		(pin "F4"
		)
		(pin "F7"
		)
		(pin "G1"
		)
		(pin "G18"
		)
		(pin "G2"
		)
		(pin "G5"
		)
		(pin "G6"
		)
		(pin "G8"
		)
		(pin "H15"
		)
		(pin "H25"
		)
		(pin "H3"
		)
		(pin "H4"
		)
		(pin "H7"
		)
		(pin "J1"
		)
		(pin "J12"
		)
		(pin "J2"
		)
		(pin "J22"
		)
		(pin "J5"
		)
		(pin "J6"
		)
		(pin "J9"
		)
		(pin "K10"
		)
		(pin "K11"
		)
		(pin "K12"
		)
		(pin "K13"
		)
		(pin "K14"
		)
		(pin "K19"
		)
		(pin "K3"
		)
		(pin "K4"
		)
		(pin "K7"
		)
		(pin "K8"
		)
		(pin "K9"
		)
		(pin "L1"
		)
		(pin "L10"
		)
		(pin "L11"
		)
		(pin "L12"
		)
		(pin "L13"
		)
		(pin "L14"
		)
		(pin "L15"
		)
		(pin "L16"
		)
		(pin "L2"
		)
		(pin "L26"
		)
		(pin "L5"
		)
		(pin "L6"
		)
		(pin "L9"
		)
		(pin "M10"
		)
		(pin "M11"
		)
		(pin "M12"
		)
		(pin "M13"
		)
		(pin "M14"
		)
		(pin "M15"
		)
		(pin "M23"
		)
		(pin "M3"
		)
		(pin "M4"
		)
		(pin "M5"
		)
		(pin "M6"
		)
		(pin "M7"
		)
		(pin "M8"
		)
		(pin "M9"
		)
		(pin "N1"
		)
		(pin "N10"
		)
		(pin "N13"
		)
		(pin "N14"
		)
		(pin "N15"
		)
		(pin "N2"
		)
		(pin "N20"
		)
		(pin "N5"
		)
		(pin "N6"
		)
		(pin "N7"
		)
		(pin "N9"
		)
		(pin "P10"
		)
		(pin "P13"
		)
		(pin "P14"
		)
		(pin "P15"
		)
		(pin "P17"
		)
		(pin "P3"
		)
		(pin "P4"
		)
		(pin "P8"
		)
		(pin "P9"
		)
		(pin "R1"
		)
		(pin "R10"
		)
		(pin "R13"
		)
		(pin "R14"
		)
		(pin "R15"
		)
		(pin "R2"
		)
		(pin "R24"
		)
		(pin "R5"
		)
		(pin "R8"
		)
		(pin "R9"
		)
		(pin "T1"
		)
		(pin "T10"
		)
		(pin "T11"
		)
		(pin "T12"
		)
		(pin "T13"
		)
		(pin "T14"
		)
		(pin "T15"
		)
		(pin "T21"
		)
		(pin "T3"
		)
		(pin "T4"
		)
		(pin "T8"
		)
		(pin "T9"
		)
		(pin "U10"
		)
		(pin "U11"
		)
		(pin "U12"
		)
		(pin "U13"
		)
		(pin "U14"
		)
		(pin "U15"
		)
		(pin "U18"
		)
		(pin "U8"
		)
		(pin "V15"
		)
		(pin "V25"
		)
		(pin "V5"
		)
		(pin "W12"
		)
		(pin "W2"
		)
		(pin "W22"
		)
		(pin "Y19"
		)
		(pin "Y9"
		)
		(pin "C8"
		)
		(pin "G7"
		)
		(pin "J7"
		)
		(pin "L7"
		)
		(pin "L8"
		)
		(pin "N11"
		)
		(pin "N12"
		)
		(pin "N8"
		)
		(pin "P11"
		)
		(pin "P12"
		)
		(pin "P5"
		)
		(pin "P6"
		)
		(pin "P7"
		)
		(pin "R11"
		)
		(pin "R12"
		)
		(pin "R6"
		)
		(pin "R7"
		)
		(pin "T2"
		)
		(pin "T5"
		)
		(pin "T6"
		)
		(instances
			(project "sodimm-ddr5-tester"
				(path ""
					(reference "U4")
					(unit 4)
				)
			)
		)
	)
	(symbol
		(lib_id "antmicroResistors0402:R_0R_0402")
		(at 83.82 83.82 0)
		(unit 1)
		(exclude_from_sim no)
		(in_bom yes)
		(on_board yes)
		(dnp no)
		(fields_autoplaced yes)
		(property "Reference" "R96"
			(at 86.36 79.246 0)
			(effects
				(font
					(size 1.27 1.27)
					(thickness 0.15)
				)
			)
		)
		(property "Value" "R_0R_0402"
			(at 104.14 96.52 0)
			(effects
				(font
					(size 1.27 1.27)
					(thickness 0.15)
				)
				(justify left bottom)
				(hide yes)
			)
		)
		(property "Footprint" "antmicro-footprints:R_0402_1005Metric"
			(at 104.14 99.06 0)
			(effects
				(font
					(size 1.27 1.27)
					(thickness 0.15)
				)
				(justify left bottom)
				(hide yes)
			)
		)
		(property "Datasheet" "https://industrial.panasonic.com/cdbs/www-data/pdf/RDA0000/AOA0000C301.pdf"
			(at 104.14 101.6 0)
			(effects
				(font
					(size 1.27 1.27)
					(thickness 0.15)
				)
				(justify left bottom)
				(hide yes)
			)
		)
		(property "Description" ""
			(at 83.82 83.82 0)
			(effects
				(font
					(size 1.27 1.27)
				)
			)
		)
		(property "MPN" "ERJ2GE0R00X"
			(at 104.14 104.14 0)
			(effects
				(font
					(size 1.27 1.27)
					(thickness 0.15)
				)
				(justify left bottom)
				(hide yes)
			)
		)
		(property "Manufacturer" "Panasonic"
			(at 104.14 106.68 0)
			(effects
				(font
					(size 1.27 1.27)
					(thickness 0.15)
				)
				(justify left bottom)
				(hide yes)
			)
		)
		(property "License" "Apache-2.0"
			(at 104.14 109.22 0)
			(effects
				(font
					(size 1.27 1.27)
					(thickness 0.15)
				)
				(justify left bottom)
				(hide yes)
			)
		)
		(property "Author" "Antmicro"
			(at 104.14 111.76 0)
			(effects
				(font
					(size 1.27 1.27)
					(thickness 0.15)
				)
				(justify left bottom)
				(hide yes)
			)
		)
		(property "Val" "0R"
			(at 86.36 81.7697 0)
			(effects
				(font
					(size 1.27 1.27)
					(thickness 0.15)
				)
			)
		)
		(property "Tolerance" "~"
			(at 104.14 93.98 0)
			(effects
				(font
					(size 1.27 1.27)
				)
				(justify left bottom)
				(hide yes)
			)
		)
		(property "Current" "1A"
			(at 104.14 114.3 0)
			(effects
				(font
					(size 1.27 1.27)
					(thickness 0.15)
				)
				(justify left bottom)
				(hide yes)
			)
		)
		(pin "1"
		)
		(pin "2"
		)
		(instances
			(project "sodimm-ddr5-tester"
				(path ""
					(reference "R96")
					(unit 1)
				)
			)
		)
	)
	(symbol
		(lib_id "antmicropower:PWR_FLAG")
		(at 278.13 83.185 0)
		(unit 1)
		(exclude_from_sim no)
		(in_bom yes)
		(on_board yes)
		(dnp no)
		(fields_autoplaced yes)
		(property "Reference" "#FLG0108"
			(at 278.13 81.28 0)
			(effects
				(font
					(size 1.27 1.27)
				)
				(hide yes)
			)
		)
		(property "Value" "PWR_FLAG"
			(at 278.13 79.6092 0)
			(effects
				(font
					(size 1.27 1.27)
				)
			)
		)
		(property "Footprint" ""
			(at 278.13 83.185 0)
			(effects
				(font
					(size 1.27 1.27)
				)
				(hide yes)
			)
		)
		(property "Datasheet" ""
			(at 278.13 83.185 0)
			(effects
				(font
					(size 1.27 1.27)
				)
				(hide yes)
			)
		)
		(property "Description" ""
			(at 278.13 83.185 0)
			(effects
				(font
					(size 1.27 1.27)
				)
			)
		)
		(pin "1"
		)
		(instances
			(project "sodimm-ddr5-tester"
				(path ""
					(reference "#FLG0108")
					(unit 1)
				)
			)
		)
	)
	(symbol
		(lib_id "antmicropower:+3V3")
		(at 80.01 81.915 0)
		(unit 1)
		(exclude_from_sim no)
		(in_bom yes)
		(on_board yes)
		(dnp no)
		(fields_autoplaced yes)
		(property "Reference" "#PWR0236"
			(at 80.01 85.725 0)
			(effects
				(font
					(size 1.27 1.27)
				)
				(hide yes)
			)
		)
		(property "Value" "+3V3"
			(at 76.835 79.375 0)
			(effects
				(font
					(size 1.27 1.27)
					(thickness 0.15)
				)
				(justify left bottom)
			)
		)
		(property "Footprint" ""
			(at 95.25 89.535 0)
			(effects
				(font
					(size 1.27 1.27)
					(thickness 0.15)
				)
				(justify left bottom)
				(hide yes)
			)
		)
		(property "Datasheet" ""
			(at 95.25 92.075 0)
			(effects
				(font
					(size 1.27 1.27)
					(thickness 0.15)
				)
				(justify left bottom)
				(hide yes)
			)
		)
		(property "Description" ""
			(at 80.01 81.915 0)
			(effects
				(font
					(size 1.27 1.27)
				)
			)
		)
		(property "Author" "Antmicro"
			(at 95.25 84.455 0)
			(effects
				(font
					(size 1.27 1.27)
					(thickness 0.15)
				)
				(justify left bottom)
				(hide yes)
			)
		)
		(property "License" "Apache-2.0"
			(at 95.25 86.995 0)
			(effects
				(font
					(size 1.27 1.27)
					(thickness 0.15)
				)
				(justify left bottom)
				(hide yes)
			)
		)
		(pin "1"
		)
		(instances
			(project "sodimm-ddr5-tester"
				(path ""
					(reference "#PWR0236")
					(unit 1)
				)
			)
		)
	)
	(symbol
		(lib_id "antmicroResistors0402:R_0R_0402")
		(at 267.97 83.82 0)
		(unit 1)
		(exclude_from_sim no)
		(in_bom yes)
		(on_board yes)
		(dnp no)
		(fields_autoplaced yes)
		(property "Reference" "R97"
			(at 270.51 79.246 0)
			(effects
				(font
					(size 1.27 1.27)
					(thickness 0.15)
				)
			)
		)
		(property "Value" "R_0R_0402"
			(at 288.29 96.52 0)
			(effects
				(font
					(size 1.27 1.27)
					(thickness 0.15)
				)
				(justify left bottom)
				(hide yes)
			)
		)
		(property "Footprint" "antmicro-footprints:R_0402_1005Metric"
			(at 288.29 99.06 0)
			(effects
				(font
					(size 1.27 1.27)
					(thickness 0.15)
				)
				(justify left bottom)
				(hide yes)
			)
		)
		(property "Datasheet" "https://industrial.panasonic.com/cdbs/www-data/pdf/RDA0000/AOA0000C301.pdf"
			(at 288.29 101.6 0)
			(effects
				(font
					(size 1.27 1.27)
					(thickness 0.15)
				)
				(justify left bottom)
				(hide yes)
			)
		)
		(property "Description" ""
			(at 267.97 83.82 0)
			(effects
				(font
					(size 1.27 1.27)
				)
			)
		)
		(property "MPN" "ERJ2GE0R00X"
			(at 288.29 104.14 0)
			(effects
				(font
					(size 1.27 1.27)
					(thickness 0.15)
				)
				(justify left bottom)
				(hide yes)
			)
		)
		(property "Manufacturer" "Panasonic"
			(at 288.29 106.68 0)
			(effects
				(font
					(size 1.27 1.27)
					(thickness 0.15)
				)
				(justify left bottom)
				(hide yes)
			)
		)
		(property "License" "Apache-2.0"
			(at 288.29 109.22 0)
			(effects
				(font
					(size 1.27 1.27)
					(thickness 0.15)
				)
				(justify left bottom)
				(hide yes)
			)
		)
		(property "Author" "Antmicro"
			(at 288.29 111.76 0)
			(effects
				(font
					(size 1.27 1.27)
					(thickness 0.15)
				)
				(justify left bottom)
				(hide yes)
			)
		)
		(property "Val" "0R"
			(at 270.51 81.7697 0)
			(effects
				(font
					(size 1.27 1.27)
					(thickness 0.15)
				)
			)
		)
		(property "Tolerance" "~"
			(at 288.29 93.98 0)
			(effects
				(font
					(size 1.27 1.27)
				)
				(justify left bottom)
				(hide yes)
			)
		)
		(property "Current" "1A"
			(at 288.29 114.3 0)
			(effects
				(font
					(size 1.27 1.27)
					(thickness 0.15)
				)
				(justify left bottom)
				(hide yes)
			)
		)
		(pin "1"
		)
		(pin "2"
		)
		(instances
			(project "sodimm-ddr5-tester"
				(path ""
					(reference "R97")
					(unit 1)
				)
			)
		)
	)
	(symbol
		(lib_id "antmicroFPGAChips:XC7K160T-FFG676")
		(at 96.52 83.82 0)
		(unit 2)
		(exclude_from_sim no)
		(in_bom yes)
		(on_board yes)
		(dnp no)
		(fields_autoplaced yes)
		(property "Reference" "U4"
			(at 130.302 147.7594 0)
			(effects
				(font
					(size 1.27 1.27)
				)
				(justify left)
			)
		)
		(property "Value" "XC7K160T-FFG676"
			(at 130.302 150.2897 0)
			(effects
				(font
					(size 1.27 1.27)
					(thickness 0.15)
				)
				(justify left)
			)
		)
		(property "Footprint" "antmicro-footprints:BGA-676_27x27mm_Layout26x26_P1x1mm_FFG676"
			(at 165.1 86.36 0)
			(effects
				(font
					(size 1.27 1.27)
					(thickness 0.15)
				)
				(justify left bottom)
				(hide yes)
			)
		)
		(property "Datasheet" "https://docs.xilinx.com/v/u/en-US/ds180_7Series_Overview"
			(at 165.1 88.9 0)
			(effects
				(font
					(size 1.27 1.27)
					(thickness 0.15)
				)
				(justify left bottom)
				(hide yes)
			)
		)
		(property "Description" ""
			(at 96.52 83.82 0)
			(effects
				(font
					(size 1.27 1.27)
				)
			)
		)
		(property "MPN" "XC7K160T-FFG676"
			(at 96.52 83.82 0)
			(effects
				(font
					(size 1.27 1.27)
				)
				(hide yes)
			)
		)
		(property "Author" "Antmicro"
			(at 165.1 91.44 0)
			(effects
				(font
					(size 1.27 1.27)
					(thickness 0.15)
				)
				(justify left bottom)
				(hide yes)
			)
		)
		(property "License" "Apache-2.0"
			(at 165.1 93.98 0)
			(effects
				(font
					(size 1.27 1.27)
					(thickness 0.15)
				)
				(justify left bottom)
				(hide yes)
			)
		)
		(property "Manufacturer" "AMD-Xilinx"
			(at 96.52 83.82 0)
			(effects
				(font
					(size 1.27 1.27)
				)
				(hide yes)
			)
		)
		(pin "AA21"
		)
		(pin "AA22"
		)
		(pin "AA23"
		)
		(pin "AA24"
		)
		(pin "AA25"
		)
		(pin "AB21"
		)
		(pin "AB22"
		)
		(pin "AB24"
		)
		(pin "AB25"
		)
		(pin "AB26"
		)
		(pin "AC21"
		)
		(pin "AC22"
		)
		(pin "AC23"
		)
		(pin "AC24"
		)
		(pin "AC25"
		)
		(pin "AC26"
		)
		(pin "AD21"
		)
		(pin "AD22"
		)
		(pin "AD23"
		)
		(pin "AD24"
		)
		(pin "AD25"
		)
		(pin "AD26"
		)
		(pin "AE21"
		)
		(pin "AE22"
		)
		(pin "AE23"
		)
		(pin "AE25"
		)
		(pin "AE26"
		)
		(pin "AF22"
		)
		(pin "AF23"
		)
		(pin "AF24"
		)
		(pin "AF25"
		)
		(pin "AF26"
		)
		(pin "U21"
		)
		(pin "U22"
		)
		(pin "U23"
		)
		(pin "U24"
		)
		(pin "U25"
		)
		(pin "U26"
		)
		(pin "V20"
		)
		(pin "V21"
		)
		(pin "V22"
		)
		(pin "V23"
		)
		(pin "V24"
		)
		(pin "V26"
		)
		(pin "W20"
		)
		(pin "W21"
		)
		(pin "W23"
		)
		(pin "W24"
		)
		(pin "W25"
		)
		(pin "W26"
		)
		(pin "Y20"
		)
		(pin "Y21"
		)
		(pin "Y22"
		)
		(pin "Y23"
		)
		(pin "Y24"
		)
		(pin "Y25"
		)
		(pin "Y26"
		)
		(pin "K24"
		)
		(pin "K25"
		)
		(pin "K26"
		)
		(pin "L24"
		)
		(pin "L25"
		)
		(pin "M19"
		)
		(pin "M20"
		)
		(pin "M21"
		)
		(pin "M22"
		)
		(pin "M24"
		)
		(pin "M25"
		)
		(pin "M26"
		)
		(pin "N16"
		)
		(pin "N17"
		)
		(pin "N18"
		)
		(pin "N19"
		)
		(pin "N21"
		)
		(pin "N22"
		)
		(pin "N23"
		)
		(pin "N24"
		)
		(pin "N25"
		)
		(pin "N26"
		)
		(pin "P16"
		)
		(pin "P18"
		)
		(pin "P19"
		)
		(pin "P20"
		)
		(pin "P21"
		)
		(pin "P22"
		)
		(pin "P23"
		)
		(pin "P24"
		)
		(pin "P25"
		)
		(pin "P26"
		)
		(pin "R16"
		)
		(pin "R17"
		)
		(pin "R18"
		)
		(pin "R19"
		)
		(pin "R20"
		)
		(pin "R21"
		)
		(pin "R22"
		)
		(pin "R23"
		)
		(pin "R25"
		)
		(pin "R26"
		)
		(pin "T16"
		)
		(pin "T17"
		)
		(pin "T18"
		)
		(pin "T19"
		)
		(pin "T20"
		)
		(pin "T22"
		)
		(pin "T23"
		)
		(pin "T24"
		)
		(pin "T25"
		)
		(pin "T26"
		)
		(pin "U16"
		)
		(pin "U17"
		)
		(pin "U19"
		)
		(pin "U20"
		)
		(pin "A20"
		)
		(pin "A21"
		)
		(pin "A22"
		)
		(pin "A23"
		)
		(pin "A24"
		)
		(pin "A25"
		)
		(pin "B20"
		)
		(pin "B21"
		)
		(pin "B22"
		)
		(pin "B24"
		)
		(pin "B25"
		)
		(pin "B26"
		)
		(pin "C21"
		)
		(pin "C22"
		)
		(pin "C23"
		)
		(pin "C24"
		)
		(pin "C25"
		)
		(pin "C26"
		)
		(pin "D21"
		)
		(pin "D22"
		)
		(pin "D23"
		)
		(pin "D24"
		)
		(pin "D25"
		)
		(pin "D26"
		)
		(pin "E21"
		)
		(pin "E22"
		)
		(pin "E23"
		)
		(pin "E25"
		)
		(pin "E26"
		)
		(pin "F22"
		)
		(pin "F23"
		)
		(pin "F24"
		)
		(pin "F25"
		)
		(pin "F26"
		)
		(pin "G21"
		)
		(pin "G22"
		)
		(pin "G23"
		)
		(pin "G24"
		)
		(pin "G25"
		)
		(pin "G26"
		)
		(pin "H21"
		)
		(pin "H22"
		)
		(pin "H23"
		)
		(pin "H24"
		)
		(pin "H26"
		)
		(pin "J21"
		)
		(pin "J23"
		)
		(pin "J24"
		)
		(pin "J25"
		)
		(pin "J26"
		)
		(pin "K21"
		)
		(pin "K22"
		)
		(pin "K23"
		)
		(pin "L21"
		)
		(pin "L22"
		)
		(pin "L23"
		)
		(pin "A17"
		)
		(pin "A18"
		)
		(pin "A19"
		)
		(pin "B16"
		)
		(pin "B17"
		)
		(pin "B18"
		)
		(pin "B19"
		)
		(pin "C16"
		)
		(pin "C17"
		)
		(pin "C18"
		)
		(pin "C19"
		)
		(pin "D15"
		)
		(pin "D16"
		)
		(pin "D18"
		)
		(pin "D19"
		)
		(pin "D20"
		)
		(pin "E15"
		)
		(pin "E16"
		)
		(pin "E17"
		)
		(pin "E18"
		)
		(pin "E19"
		)
		(pin "E20"
		)
		(pin "F15"
		)
		(pin "F16"
		)
		(pin "F17"
		)
		(pin "F18"
		)
		(pin "F19"
		)
		(pin "F20"
		)
		(pin "G15"
		)
		(pin "G16"
		)
		(pin "G17"
		)
		(pin "G19"
		)
		(pin "G20"
		)
		(pin "H16"
		)
		(pin "H17"
		)
		(pin "H18"
		)
		(pin "H19"
		)
		(pin "H20"
		)
		(pin "J15"
		)
		(pin "J16"
		)
		(pin "J17"
		)
		(pin "J18"
		)
		(pin "J19"
		)
		(pin "J20"
		)
		(pin "K15"
		)
		(pin "K16"
		)
		(pin "K17"
		)
		(pin "K18"
		)
		(pin "K20"
		)
		(pin "L17"
		)
		(pin "L18"
		)
		(pin "L19"
		)
		(pin "L20"
		)
		(pin "M16"
		)
		(pin "M17"
		)
		(pin "M18"
		)
		(pin "A10"
		)
		(pin "A11"
		)
		(pin "A12"
		)
		(pin "A13"
		)
		(pin "A14"
		)
		(pin "A15"
		)
		(pin "A8"
		)
		(pin "A9"
		)
		(pin "B10"
		)
		(pin "B11"
		)
		(pin "B12"
		)
		(pin "B14"
		)
		(pin "B15"
		)
		(pin "B8"
		)
		(pin "B9"
		)
		(pin "C11"
		)
		(pin "C12"
		)
		(pin "C13"
		)
		(pin "C14"
		)
		(pin "C15"
		)
		(pin "C9"
		)
		(pin "D10"
		)
		(pin "D11"
		)
		(pin "D12"
		)
		(pin "D13"
		)
		(pin "D14"
		)
		(pin "D8"
		)
		(pin "D9"
		)
		(pin "E10"
		)
		(pin "E11"
		)
		(pin "E12"
		)
		(pin "E13"
		)
		(pin "E9"
		)
		(pin "F10"
		)
		(pin "F12"
		)
		(pin "F13"
		)
		(pin "F14"
		)
		(pin "F8"
		)
		(pin "F9"
		)
		(pin "G10"
		)
		(pin "G11"
		)
		(pin "G12"
		)
		(pin "G13"
		)
		(pin "G14"
		)
		(pin "G9"
		)
		(pin "H10"
		)
		(pin "H11"
		)
		(pin "H12"
		)
		(pin "H13"
		)
		(pin "H14"
		)
		(pin "H8"
		)
		(pin "H9"
		)
		(pin "J10"
		)
		(pin "J11"
		)
		(pin "J13"
		)
		(pin "J14"
		)
		(pin "J8"
		)
		(pin "AA14"
		)
		(pin "AA15"
		)
		(pin "AA17"
		)
		(pin "AA18"
		)
		(pin "AA19"
		)
		(pin "AA20"
		)
		(pin "AB14"
		)
		(pin "AB15"
		)
		(pin "AB16"
		)
		(pin "AB17"
		)
		(pin "AB18"
		)
		(pin "AB19"
		)
		(pin "AB20"
		)
		(pin "AC14"
		)
		(pin "AC15"
		)
		(pin "AC16"
		)
		(pin "AC17"
		)
		(pin "AC18"
		)
		(pin "AC19"
		)
		(pin "AD14"
		)
		(pin "AD15"
		)
		(pin "AD16"
		)
		(pin "AD18"
		)
		(pin "AD19"
		)
		(pin "AD20"
		)
		(pin "AE15"
		)
		(pin "AE16"
		)
		(pin "AE17"
		)
		(pin "AE18"
		)
		(pin "AE19"
		)
		(pin "AE20"
		)
		(pin "AF14"
		)
		(pin "AF15"
		)
		(pin "AF16"
		)
		(pin "AF17"
		)
		(pin "AF18"
		)
		(pin "AF19"
		)
		(pin "AF20"
		)
		(pin "V13"
		)
		(pin "V14"
		)
		(pin "V16"
		)
		(pin "V17"
		)
		(pin "V18"
		)
		(pin "V19"
		)
		(pin "W13"
		)
		(pin "W14"
		)
		(pin "W15"
		)
		(pin "W16"
		)
		(pin "W17"
		)
		(pin "W18"
		)
		(pin "W19"
		)
		(pin "Y14"
		)
		(pin "Y15"
		)
		(pin "Y16"
		)
		(pin "Y17"
		)
		(pin "Y18"
		)
		(pin "AA10"
		)
		(pin "AA11"
		)
		(pin "AA12"
		)
		(pin "AA13"
		)
		(pin "AA7"
		)
		(pin "AA8"
		)
		(pin "AA9"
		)
		(pin "AB10"
		)
		(pin "AB11"
		)
		(pin "AB12"
		)
		(pin "AB7"
		)
		(pin "AB8"
		)
		(pin "AB9"
		)
		(pin "AC11"
		)
		(pin "AC12"
		)
		(pin "AC13"
		)
		(pin "AC7"
		)
		(pin "AC8"
		)
		(pin "AC9"
		)
		(pin "AD10"
		)
		(pin "AD11"
		)
		(pin "AD12"
		)
		(pin "AD13"
		)
		(pin "AD8"
		)
		(pin "AD9"
		)
		(pin "AE10"
		)
		(pin "AE11"
		)
		(pin "AE12"
		)
		(pin "AE13"
		)
		(pin "AE7"
		)
		(pin "AE8"
		)
		(pin "AE9"
		)
		(pin "AF10"
		)
		(pin "AF12"
		)
		(pin "AF13"
		)
		(pin "AF7"
		)
		(pin "AF8"
		)
		(pin "AF9"
		)
		(pin "U9"
		)
		(pin "V10"
		)
		(pin "V11"
		)
		(pin "V12"
		)
		(pin "V7"
		)
		(pin "V8"
		)
		(pin "V9"
		)
		(pin "W10"
		)
		(pin "W11"
		)
		(pin "W7"
		)
		(pin "W8"
		)
		(pin "W9"
		)
		(pin "Y10"
		)
		(pin "Y11"
		)
		(pin "Y12"
		)
		(pin "Y13"
		)
		(pin "Y7"
		)
		(pin "Y8"
		)
		(pin "AA1"
		)
		(pin "AA2"
		)
		(pin "AA3"
		)
		(pin "AA4"
		)
		(pin "AA5"
		)
		(pin "AB1"
		)
		(pin "AB2"
		)
		(pin "AB4"
		)
		(pin "AB5"
		)
		(pin "AB6"
		)
		(pin "AC1"
		)
		(pin "AC2"
		)
		(pin "AC3"
		)
		(pin "AC4"
		)
		(pin "AC5"
		)
		(pin "AC6"
		)
		(pin "AD1"
		)
		(pin "AD2"
		)
		(pin "AD3"
		)
		(pin "AD4"
		)
		(pin "AD5"
		)
		(pin "AD6"
		)
		(pin "AE1"
		)
		(pin "AE2"
		)
		(pin "AE3"
		)
		(pin "AE5"
		)
		(pin "AE6"
		)
		(pin "AF2"
		)
		(pin "AF3"
		)
		(pin "AF4"
		)
		(pin "AF5"
		)
		(pin "AF6"
		)
		(pin "T7"
		)
		(pin "U1"
		)
		(pin "U2"
		)
		(pin "U3"
		)
		(pin "U4"
		)
		(pin "U5"
		)
		(pin "U6"
		)
		(pin "U7"
		)
		(pin "V1"
		)
		(pin "V2"
		)
		(pin "V3"
		)
		(pin "V4"
		)
		(pin "V6"
		)
		(pin "W1"
		)
		(pin "W3"
		)
		(pin "W4"
		)
		(pin "W5"
		)
		(pin "W6"
		)
		(pin "Y1"
		)
		(pin "Y2"
		)
		(pin "Y3"
		)
		(pin "Y4"
		)
		(pin "Y5"
		)
		(pin "Y6"
		)
		(pin "A3"
		)
		(pin "A4"
		)
		(pin "B1"
		)
		(pin "B2"
		)
		(pin "B5"
		)
		(pin "B6"
		)
		(pin "C3"
		)
		(pin "C4"
		)
		(pin "D1"
		)
		(pin "D2"
		)
		(pin "D5"
		)
		(pin "D6"
		)
		(pin "E3"
		)
		(pin "E4"
		)
		(pin "F1"
		)
		(pin "F2"
		)
		(pin "F5"
		)
		(pin "F6"
		)
		(pin "G3"
		)
		(pin "G4"
		)
		(pin "H1"
		)
		(pin "H2"
		)
		(pin "H5"
		)
		(pin "H6"
		)
		(pin "J3"
		)
		(pin "J4"
		)
		(pin "K1"
		)
		(pin "K2"
		)
		(pin "K5"
		)
		(pin "K6"
		)
		(pin "L3"
		)
		(pin "L4"
		)
		(pin "M1"
		)
		(pin "M2"
		)
		(pin "N3"
		)
		(pin "N4"
		)
		(pin "P1"
		)
		(pin "P2"
		)
		(pin "R3"
		)
		(pin "R4"
		)
		(pin "A1"
		)
		(pin "A16"
		)
		(pin "A2"
		)
		(pin "A26"
		)
		(pin "A5"
		)
		(pin "A6"
		)
		(pin "A7"
		)
		(pin "AA16"
		)
		(pin "AA26"
		)
		(pin "AA6"
		)
		(pin "AB13"
		)
		(pin "AB23"
		)
		(pin "AB3"
		)
		(pin "AC10"
		)
		(pin "AC20"
		)
		(pin "AD17"
		)
		(pin "AD7"
		)
		(pin "AE14"
		)
		(pin "AE24"
		)
		(pin "AE4"
		)
		(pin "AF1"
		)
		(pin "AF11"
		)
		(pin "AF21"
		)
		(pin "B13"
		)
		(pin "B23"
		)
		(pin "B3"
		)
		(pin "B4"
		)
		(pin "B7"
		)
		(pin "C1"
		)
		(pin "C10"
		)
		(pin "C2"
		)
		(pin "C20"
		)
		(pin "C5"
		)
		(pin "C6"
		)
		(pin "C7"
		)
		(pin "D17"
		)
		(pin "D3"
		)
		(pin "D4"
		)
		(pin "D7"
		)
		(pin "E1"
		)
		(pin "E14"
		)
		(pin "E2"
		)
		(pin "E24"
		)
		(pin "E5"
		)
		(pin "E6"
		)
		(pin "E7"
		)
		(pin "E8"
		)
		(pin "F11"
		)
		(pin "F21"
		)
		(pin "F3"
		)
		(pin "F4"
		)
		(pin "F7"
		)
		(pin "G1"
		)
		(pin "G18"
		)
		(pin "G2"
		)
		(pin "G5"
		)
		(pin "G6"
		)
		(pin "G8"
		)
		(pin "H15"
		)
		(pin "H25"
		)
		(pin "H3"
		)
		(pin "H4"
		)
		(pin "H7"
		)
		(pin "J1"
		)
		(pin "J12"
		)
		(pin "J2"
		)
		(pin "J22"
		)
		(pin "J5"
		)
		(pin "J6"
		)
		(pin "J9"
		)
		(pin "K10"
		)
		(pin "K11"
		)
		(pin "K12"
		)
		(pin "K13"
		)
		(pin "K14"
		)
		(pin "K19"
		)
		(pin "K3"
		)
		(pin "K4"
		)
		(pin "K7"
		)
		(pin "K8"
		)
		(pin "K9"
		)
		(pin "L1"
		)
		(pin "L10"
		)
		(pin "L11"
		)
		(pin "L12"
		)
		(pin "L13"
		)
		(pin "L14"
		)
		(pin "L15"
		)
		(pin "L16"
		)
		(pin "L2"
		)
		(pin "L26"
		)
		(pin "L5"
		)
		(pin "L6"
		)
		(pin "L9"
		)
		(pin "M10"
		)
		(pin "M11"
		)
		(pin "M12"
		)
		(pin "M13"
		)
		(pin "M14"
		)
		(pin "M15"
		)
		(pin "M23"
		)
		(pin "M3"
		)
		(pin "M4"
		)
		(pin "M5"
		)
		(pin "M6"
		)
		(pin "M7"
		)
		(pin "M8"
		)
		(pin "M9"
		)
		(pin "N1"
		)
		(pin "N10"
		)
		(pin "N13"
		)
		(pin "N14"
		)
		(pin "N15"
		)
		(pin "N2"
		)
		(pin "N20"
		)
		(pin "N5"
		)
		(pin "N6"
		)
		(pin "N7"
		)
		(pin "N9"
		)
		(pin "P10"
		)
		(pin "P13"
		)
		(pin "P14"
		)
		(pin "P15"
		)
		(pin "P17"
		)
		(pin "P3"
		)
		(pin "P4"
		)
		(pin "P8"
		)
		(pin "P9"
		)
		(pin "R1"
		)
		(pin "R10"
		)
		(pin "R13"
		)
		(pin "R14"
		)
		(pin "R15"
		)
		(pin "R2"
		)
		(pin "R24"
		)
		(pin "R5"
		)
		(pin "R8"
		)
		(pin "R9"
		)
		(pin "T1"
		)
		(pin "T10"
		)
		(pin "T11"
		)
		(pin "T12"
		)
		(pin "T13"
		)
		(pin "T14"
		)
		(pin "T15"
		)
		(pin "T21"
		)
		(pin "T3"
		)
		(pin "T4"
		)
		(pin "T8"
		)
		(pin "T9"
		)
		(pin "U10"
		)
		(pin "U11"
		)
		(pin "U12"
		)
		(pin "U13"
		)
		(pin "U14"
		)
		(pin "U15"
		)
		(pin "U18"
		)
		(pin "U8"
		)
		(pin "V15"
		)
		(pin "V25"
		)
		(pin "V5"
		)
		(pin "W12"
		)
		(pin "W2"
		)
		(pin "W22"
		)
		(pin "Y19"
		)
		(pin "Y9"
		)
		(pin "C8"
		)
		(pin "G7"
		)
		(pin "J7"
		)
		(pin "L7"
		)
		(pin "L8"
		)
		(pin "N11"
		)
		(pin "N12"
		)
		(pin "N8"
		)
		(pin "P11"
		)
		(pin "P12"
		)
		(pin "P5"
		)
		(pin "P6"
		)
		(pin "P7"
		)
		(pin "R11"
		)
		(pin "R12"
		)
		(pin "R6"
		)
		(pin "R7"
		)
		(pin "T2"
		)
		(pin "T5"
		)
		(pin "T6"
		)
		(instances
			(project "sodimm-ddr5-tester"
				(path ""
					(reference "U4")
					(unit 2)
				)
			)
		)
	)
	(symbol
		(lib_id "antmicropower:PWR_FLAG")
		(at 93.98 83.185 0)
		(unit 1)
		(exclude_from_sim no)
		(in_bom yes)
		(on_board yes)
		(dnp no)
		(fields_autoplaced yes)
		(property "Reference" "#FLG0109"
			(at 93.98 81.28 0)
			(effects
				(font
					(size 1.27 1.27)
				)
				(hide yes)
			)
		)
		(property "Value" "PWR_FLAG"
			(at 93.98 79.6092 0)
			(effects
				(font
					(size 1.27 1.27)
				)
			)
		)
		(property "Footprint" ""
			(at 93.98 83.185 0)
			(effects
				(font
					(size 1.27 1.27)
				)
				(hide yes)
			)
		)
		(property "Datasheet" ""
			(at 93.98 83.185 0)
			(effects
				(font
					(size 1.27 1.27)
				)
				(hide yes)
			)
		)
		(property "Description" ""
			(at 93.98 83.185 0)
			(effects
				(font
					(size 1.27 1.27)
				)
			)
		)
		(pin "1"
		)
		(instances
			(project "sodimm-ddr5-tester"
				(path ""
					(reference "#FLG0109")
					(unit 1)
				)
			)
		)
	)
	(symbol
		(lib_id "antmicropower:+3V3")
		(at 264.16 81.915 0)
		(unit 1)
		(exclude_from_sim no)
		(in_bom yes)
		(on_board yes)
		(dnp no)
		(fields_autoplaced yes)
		(property "Reference" "#PWR0238"
			(at 264.16 85.725 0)
			(effects
				(font
					(size 1.27 1.27)
				)
				(hide yes)
			)
		)
		(property "Value" "+3V3"
			(at 260.985 79.375 0)
			(effects
				(font
					(size 1.27 1.27)
					(thickness 0.15)
				)
				(justify left bottom)
			)
		)
		(property "Footprint" ""
			(at 279.4 89.535 0)
			(effects
				(font
					(size 1.27 1.27)
					(thickness 0.15)
				)
				(justify left bottom)
				(hide yes)
			)
		)
		(property "Datasheet" ""
			(at 279.4 92.075 0)
			(effects
				(font
					(size 1.27 1.27)
					(thickness 0.15)
				)
				(justify left bottom)
				(hide yes)
			)
		)
		(property "Description" ""
			(at 264.16 81.915 0)
			(effects
				(font
					(size 1.27 1.27)
				)
			)
		)
		(property "Author" "Antmicro"
			(at 279.4 84.455 0)
			(effects
				(font
					(size 1.27 1.27)
					(thickness 0.15)
				)
				(justify left bottom)
				(hide yes)
			)
		)
		(property "License" "Apache-2.0"
			(at 279.4 86.995 0)
			(effects
				(font
					(size 1.27 1.27)
					(thickness 0.15)
				)
				(justify left bottom)
				(hide yes)
			)
		)
		(pin "1"
		)
		(instances
			(project "sodimm-ddr5-tester"
				(path ""
					(reference "#PWR0238")
					(unit 1)
				)
			)
		)
	)
)
